(kicad_pcb
	(version 20260206)
	(generator "pcbnew")
	(generator_version "10.0")
	(general
		(thickness 1.6)
		(legacy_teardrops no)
	)
	(paper "A4")
	(title_block
		(title "Bryce Canyon_SCC_16316-1_OCP.brd")
		(comment 1 "Bryce Canyon / footprints 65-72 of 1561")
	)
	(layers
		(0 "F.Cu" signal "TOP")
		(4 "In1.Cu" signal "L2GND")
		(6 "In2.Cu" signal "L3")
		(8 "In3.Cu" signal "L4VCC")
		(10 "In4.Cu" signal "L5VCC")
		(12 "In5.Cu" signal "L6")
		(14 "In6.Cu" signal "L7GND")
		(2 "B.Cu" signal "BOTTOM")
		(9 "F.Adhes" user "F.Adhesive")
		(11 "B.Adhes" user "B.Adhesive")
		(13 "F.Paste" user "Package Geometry/Pastemask Top")
		(15 "B.Paste" user "Package Geometry/Pastemask Bottom")
		(5 "F.SilkS" user "Ref Des/Silkscreen Top")
		(7 "B.SilkS" user "Ref Des/Silkscreen Bottom")
		(1 "F.Mask" user "Board Geometry/Soldermask Top")
		(3 "B.Mask" user "Board Geometry/Soldermask Bottom")
		(17 "Dwgs.User" user "User.Drawings")
		(19 "Cmts.User" user "User.Comments")
		(21 "Eco1.User" user "User.Eco1")
		(23 "Eco2.User" user "User.Eco2")
		(25 "Edge.Cuts" user "Board Geometry/Outline")
		(27 "Margin" user)
		(31 "F.CrtYd" user "Package Geometry/Place Bound Top")
		(29 "B.CrtYd" user "Package Geometry/Place Bound Bottom")
		(35 "F.Fab" user "Ref Des/Assembly Top")
		(33 "B.Fab" user "Ref Des/Assembly Bottom")
	)
	(footprint ""
		(layer "F.Cu")
		(at 49.570894 -32.973518 180)
		(property "Reference" "R401"
			(at 0 0 180)
			(layer "F.SilkS")
			(hide yes)
			(effects
				(font
					(size 1.27 1.27)
				)
			)
		)
		(property "Value" "62KR2J-GP"
			(at 0.064008 -3.993896 180)
			(unlocked yes)
			(layer "F.Fab")
			(hide yes)
			(effects
				(font
					(size 1.016 1.016)
					(thickness 0.1524)
				)
			)
		)
		(property "Device Type" "R402H16"
			(at 0.064008 -5.517896 180)
			(unlocked yes)
			(layer "F.Fab")
			(hide yes)
			(effects
				(font
					(size 1.016 1.016)
					(thickness 0.1524)
				)
			)
		)
		(duplicate_pad_numbers_are_jumpers no)
		(fp_line
			(start 0.508 -0.9398)
			(end -0.508 -0.9398)
			(stroke
				(width 0.1524)
				(type default)
			)
			(layer "F.SilkS")
		)
		(fp_line
			(start -0.508 -0.9398)
			(end -0.508 0.9398)
			(stroke
				(width 0.1524)
				(type default)
			)
			(layer "F.SilkS")
		)
		(fp_rect
			(start -0.508 0.9398)
			(end 0.508 -0.9398)
			(stroke
				(width 0)
				(type default)
			)
			(fill no)
			(layer "F.CrtYd")
		)
		(fp_rect
			(start -0.508 0.9398)
			(end 0.508 -0.9398)
			(stroke
				(width 0)
				(type default)
			)
			(fill no)
			(layer "F.Fab")
		)
		(pad "1" smd custom
			(at 0 -0.4445 180)
			(size 0.1397 0.1397)
			(layers "F.Cu" "F.Mask" "F.Paste")
			(net "P0V9_TRIP")
			(options
				(clearance outline)
				(anchor circle)
			)
			(primitives
				(gr_poly
					(pts
						(arc
							(start -0.1778 -0.2794)
							(mid -0.249642 -0.249642)
							(end -0.2794 -0.1778)
						)
						(arc
							(start -0.2794 0.1778)
							(mid -0.249642 0.249642)
							(end -0.1778 0.2794)
						)
						(arc
							(start 0.1778 0.2794)
							(mid 0.249642 0.249642)
							(end 0.2794 0.1778)
						)
						(arc
							(start 0.2794 -0.1778)
							(mid 0.249642 -0.249642)
							(end 0.1778 -0.2794)
						)
					)
					(width 0)
					(fill yes)
				)
			)
		)
		(pad "2" smd custom
			(at 0 0.4445 180)
			(size 0.1397 0.1397)
			(layers "F.Cu" "F.Mask" "F.Paste")
			(net "AGND_P0V9")
			(options
				(clearance outline)
				(anchor circle)
			)
			(primitives
				(gr_poly
					(pts
						(arc
							(start -0.1778 -0.2794)
							(mid -0.249642 -0.249642)
							(end -0.2794 -0.1778)
						)
						(arc
							(start -0.2794 0.1778)
							(mid -0.249642 0.249642)
							(end -0.1778 0.2794)
						)
						(arc
							(start 0.1778 0.2794)
							(mid 0.249642 0.249642)
							(end 0.2794 0.1778)
						)
						(arc
							(start 0.2794 -0.1778)
							(mid 0.249642 -0.249642)
							(end 0.1778 -0.2794)
						)
					)
					(width 0)
					(fill yes)
				)
			)
		)
	)
	(footprint ""
		(layer "F.Cu")
		(at 41.7576 -49.7332 180)
		(property "Reference" "C669"
			(at 0 0 180)
			(layer "F.SilkS")
			(hide yes)
			(effects
				(font
					(size 1.27 1.27)
				)
			)
		)
		(property "Value" "SC10U16V5KX-7-GP-U"
			(at -0.0762 -6.1214 180)
			(unlocked yes)
			(layer "F.Fab")
			(hide yes)
			(effects
				(font
					(size 1.016 1.016)
					(thickness 0.1524)
				)
			)
		)
		(property "Device Type" "C805H58"
			(at -0.0762 -8.1534 180)
			(unlocked yes)
			(layer "F.Fab")
			(hide yes)
			(effects
				(font
					(size 1.016 1.016)
					(thickness 0.1524)
				)
			)
		)
		(duplicate_pad_numbers_are_jumpers no)
		(fp_line
			(start 0.635 0)
			(end -0.635 0)
			(stroke
				(width 0.508)
				(type default)
			)
			(layer "F.SilkS")
		)
		(fp_rect
			(start -0.9652 1.778)
			(end 0.9652 -1.778)
			(stroke
				(width 0)
				(type default)
			)
			(fill no)
			(layer "F.CrtYd")
		)
		(fp_poly
			(pts
				(xy -0.9652 -1.778) (xy 0.9652 -1.778) (xy 0.9652 1.778) (xy -0.9652 1.778)
			)
			(stroke
				(width 0)
				(type default)
			)
			(fill no)
			(layer "F.Fab")
		)
		(pad "1" smd rect
			(at 0 -0.9652 180)
			(size 1.397 1.143)
			(layers "F.Cu" "F.Mask" "F.Paste")
			(net "P12V_STBY_VIN_Q7")
		)
		(pad "2" smd rect
			(at 0 0.9652 180)
			(size 1.397 1.143)
			(layers "F.Cu" "F.Mask" "F.Paste")
			(net "GND")
		)
	)
	(footprint ""
		(layer "F.Cu")
		(at 159.416242 -121.369074 90)
		(property "Reference" "R324"
			(at 0 0 90)
			(layer "F.SilkS")
			(hide yes)
			(effects
				(font
					(size 1.27 1.27)
				)
			)
		)
		(property "Value" "100KR2F-L1-GP"
			(at 0.064008 -3.993896 90)
			(unlocked yes)
			(layer "F.Fab")
			(hide yes)
			(effects
				(font
					(size 1.016 1.016)
					(thickness 0.1524)
				)
			)
		)
		(property "Device Type" "R402H16"
			(at 0.064008 -5.517896 90)
			(unlocked yes)
			(layer "F.Fab")
			(hide yes)
			(effects
				(font
					(size 1.016 1.016)
					(thickness 0.1524)
				)
			)
		)
		(duplicate_pad_numbers_are_jumpers no)
		(fp_line
			(start 0.508 -0.9398)
			(end -0.508 -0.9398)
			(stroke
				(width 0.1524)
				(type default)
			)
			(layer "F.SilkS")
		)
		(fp_line
			(start -0.508 -0.9398)
			(end -0.508 0.9398)
			(stroke
				(width 0.1524)
				(type default)
			)
			(layer "F.SilkS")
		)
		(fp_rect
			(start -0.508 0.9398)
			(end 0.508 -0.9398)
			(stroke
				(width 0)
				(type default)
			)
			(fill no)
			(layer "F.CrtYd")
		)
		(fp_rect
			(start -0.508 0.9398)
			(end 0.508 -0.9398)
			(stroke
				(width 0)
				(type default)
			)
			(fill no)
			(layer "F.Fab")
		)
		(pad "1" smd custom
			(at 0 -0.4445 90)
			(size 0.1397 0.1397)
			(layers "F.Cu" "F.Mask" "F.Paste")
			(net "AGND_P1V5_E")
			(options
				(clearance outline)
				(anchor circle)
			)
			(primitives
				(gr_poly
					(pts
						(arc
							(start -0.1778 -0.2794)
							(mid -0.249642 -0.249642)
							(end -0.2794 -0.1778)
						)
						(arc
							(start -0.2794 0.1778)
							(mid -0.249642 0.249642)
							(end -0.1778 0.2794)
						)
						(arc
							(start 0.1778 0.2794)
							(mid 0.249642 0.249642)
							(end 0.2794 0.1778)
						)
						(arc
							(start 0.2794 -0.1778)
							(mid 0.249642 -0.249642)
							(end 0.1778 -0.2794)
						)
					)
					(width 0)
					(fill yes)
				)
			)
		)
		(pad "2" smd custom
			(at 0 0.4445 90)
			(size 0.1397 0.1397)
			(layers "F.Cu" "F.Mask" "F.Paste")
			(net "P1V5_E_MODE")
			(options
				(clearance outline)
				(anchor circle)
			)
			(primitives
				(gr_poly
					(pts
						(arc
							(start -0.1778 -0.2794)
							(mid -0.249642 -0.249642)
							(end -0.2794 -0.1778)
						)
						(arc
							(start -0.2794 0.1778)
							(mid -0.249642 0.249642)
							(end -0.1778 0.2794)
						)
						(arc
							(start 0.1778 0.2794)
							(mid 0.249642 0.249642)
							(end 0.2794 0.1778)
						)
						(arc
							(start 0.2794 -0.1778)
							(mid 0.249642 -0.249642)
							(end 0.1778 -0.2794)
						)
					)
					(width 0)
					(fill yes)
				)
			)
		)
	)
	(footprint ""
		(layer "F.Cu")
		(at 7.0866 -57.785 90)
		(property "Reference" "R548"
			(at 0 0 90)
			(layer "F.SilkS")
			(hide yes)
			(effects
				(font
					(size 1.27 1.27)
				)
			)
		)
		(property "Value" "45K3R2F-L-GP"
			(at 0.064008 -3.993896 90)
			(unlocked yes)
			(layer "F.Fab")
			(hide yes)
			(effects
				(font
					(size 1.016 1.016)
					(thickness 0.1524)
				)
			)
		)
		(property "Device Type" "R402H16"
			(at 0.064008 -5.517896 90)
			(unlocked yes)
			(layer "F.Fab")
			(hide yes)
			(effects
				(font
					(size 1.016 1.016)
					(thickness 0.1524)
				)
			)
		)
		(duplicate_pad_numbers_are_jumpers no)
		(fp_line
			(start 0.508 -0.9398)
			(end -0.508 -0.9398)
			(stroke
				(width 0.1524)
				(type default)
			)
			(layer "F.SilkS")
		)
		(fp_line
			(start -0.508 -0.9398)
			(end -0.508 0.9398)
			(stroke
				(width 0.1524)
				(type default)
			)
			(layer "F.SilkS")
		)
		(fp_rect
			(start -0.508 0.9398)
			(end 0.508 -0.9398)
			(stroke
				(width 0)
				(type default)
			)
			(fill no)
			(layer "F.CrtYd")
		)
		(fp_rect
			(start -0.508 0.9398)
			(end 0.508 -0.9398)
			(stroke
				(width 0)
				(type default)
			)
			(fill no)
			(layer "F.Fab")
		)
		(pad "1" smd custom
			(at 0 -0.4445 90)
			(size 0.1397 0.1397)
			(layers "F.Cu" "F.Mask" "F.Paste")
			(net "P12V_STBY_SCC")
			(options
				(clearance outline)
				(anchor circle)
			)
			(primitives
				(gr_poly
					(pts
						(arc
							(start -0.1778 -0.2794)
							(mid -0.249642 -0.249642)
							(end -0.2794 -0.1778)
						)
						(arc
							(start -0.2794 0.1778)
							(mid -0.249642 0.249642)
							(end -0.1778 0.2794)
						)
						(arc
							(start 0.1778 0.2794)
							(mid 0.249642 0.249642)
							(end 0.2794 0.1778)
						)
						(arc
							(start 0.2794 -0.1778)
							(mid 0.249642 -0.249642)
							(end 0.1778 -0.2794)
						)
					)
					(width 0)
					(fill yes)
				)
			)
		)
		(pad "2" smd custom
			(at 0 0.4445 90)
			(size 0.1397 0.1397)
			(layers "F.Cu" "F.Mask" "F.Paste")
			(net "P12V_SCC_PGOOD")
			(options
				(clearance outline)
				(anchor circle)
			)
			(primitives
				(gr_poly
					(pts
						(arc
							(start -0.1778 -0.2794)
							(mid -0.249642 -0.249642)
							(end -0.2794 -0.1778)
						)
						(arc
							(start -0.2794 0.1778)
							(mid -0.249642 0.249642)
							(end -0.1778 0.2794)
						)
						(arc
							(start 0.1778 0.2794)
							(mid 0.249642 0.249642)
							(end 0.2794 0.1778)
						)
						(arc
							(start 0.2794 -0.1778)
							(mid 0.249642 -0.249642)
							(end 0.1778 -0.2794)
						)
					)
					(width 0)
					(fill yes)
				)
			)
		)
	)
	(footprint ""
		(layer "F.Cu")
		(at 127.6858 -87.2744 180)
		(property "Reference" "R102"
			(at 0 0 180)
			(layer "F.SilkS")
			(hide yes)
			(effects
				(font
					(size 1.27 1.27)
				)
			)
		)
		(property "Value" "0R2J-2-GP"
			(at 0.064008 -3.993896 180)
			(unlocked yes)
			(layer "F.Fab")
			(hide yes)
			(effects
				(font
					(size 1.016 1.016)
					(thickness 0.1524)
				)
			)
		)
		(property "Device Type" "R402H16"
			(at 0.064008 -5.517896 180)
			(unlocked yes)
			(layer "F.Fab")
			(hide yes)
			(effects
				(font
					(size 1.016 1.016)
					(thickness 0.1524)
				)
			)
		)
		(duplicate_pad_numbers_are_jumpers no)
		(fp_line
			(start 0.508 -0.9398)
			(end -0.508 -0.9398)
			(stroke
				(width 0.1524)
				(type default)
			)
			(layer "F.SilkS")
		)
		(fp_line
			(start -0.508 -0.9398)
			(end -0.508 0.9398)
			(stroke
				(width 0.1524)
				(type default)
			)
			(layer "F.SilkS")
		)
		(fp_rect
			(start -0.508 0.9398)
			(end 0.508 -0.9398)
			(stroke
				(width 0)
				(type default)
			)
			(fill no)
			(layer "F.CrtYd")
		)
		(fp_rect
			(start -0.508 0.9398)
			(end 0.508 -0.9398)
			(stroke
				(width 0)
				(type default)
			)
			(fill no)
			(layer "F.Fab")
		)
		(pad "1" smd custom
			(at 0 -0.4445 180)
			(size 0.1397 0.1397)
			(layers "F.Cu" "F.Mask" "F.Paste")
			(net "SDB_R_TX")
			(options
				(clearance outline)
				(anchor circle)
			)
			(primitives
				(gr_poly
					(pts
						(arc
							(start -0.1778 -0.2794)
							(mid -0.249642 -0.249642)
							(end -0.2794 -0.1778)
						)
						(arc
							(start -0.2794 0.1778)
							(mid -0.249642 0.249642)
							(end -0.1778 0.2794)
						)
						(arc
							(start 0.1778 0.2794)
							(mid 0.249642 0.249642)
							(end 0.2794 0.1778)
						)
						(arc
							(start 0.2794 -0.1778)
							(mid 0.249642 -0.249642)
							(end 0.1778 -0.2794)
						)
					)
					(width 0)
					(fill yes)
				)
			)
		)
		(pad "2" smd custom
			(at 0 0.4445 180)
			(size 0.1397 0.1397)
			(layers "F.Cu" "F.Mask" "F.Paste")
			(net "SDB_TX")
			(options
				(clearance outline)
				(anchor circle)
			)
			(primitives
				(gr_poly
					(pts
						(arc
							(start -0.1778 -0.2794)
							(mid -0.249642 -0.249642)
							(end -0.2794 -0.1778)
						)
						(arc
							(start -0.2794 0.1778)
							(mid -0.249642 0.249642)
							(end -0.1778 0.2794)
						)
						(arc
							(start 0.1778 0.2794)
							(mid 0.249642 0.249642)
							(end 0.2794 0.1778)
						)
						(arc
							(start 0.2794 -0.1778)
							(mid 0.249642 -0.249642)
							(end 0.1778 -0.2794)
						)
					)
					(width 0)
					(fill yes)
				)
			)
		)
	)
	(footprint ""
		(layer "F.Cu")
		(at 89.535 -88.265 -90)
		(property "Reference" "C113"
			(at 0 0 270)
			(layer "F.SilkS")
			(hide yes)
			(effects
				(font
					(size 1.27 1.27)
				)
			)
		)
		(property "Value" "SCD01U25V2KX-3GP"
			(at 1.1811 -2.7051 270)
			(unlocked yes)
			(layer "F.Fab")
			(hide yes)
			(effects
				(font
					(size 1.016 1.016)
					(thickness 0.1524)
				)
			)
		)
		(property "Device Type" "C402H22"
			(at 1.1811 -4.2291 270)
			(unlocked yes)
			(layer "F.Fab")
			(hide yes)
			(effects
				(font
					(size 1.016 1.016)
					(thickness 0.1524)
				)
			)
		)
		(duplicate_pad_numbers_are_jumpers no)
		(fp_rect
			(start -0.4318 0.9525)
			(end 0.4318 -0.9525)
			(stroke
				(width 0)
				(type default)
			)
			(fill no)
			(layer "F.CrtYd")
		)
		(fp_rect
			(start -0.4318 0.9525)
			(end 0.4318 -0.9525)
			(stroke
				(width 0)
				(type default)
			)
			(fill no)
			(layer "F.Fab")
		)
		(pad "1" smd custom
			(at 0 -0.4445 270)
			(size 0.1524 0.1524)
			(layers "F.Cu" "F.Mask" "F.Paste")
			(net "GND")
			(options
				(clearance outline)
				(anchor circle)
			)
			(primitives
				(gr_poly
					(pts
						(arc
							(start 0.3048 -0.2032)
							(mid 0.275042 -0.275042)
							(end 0.2032 -0.3048)
						)
						(arc
							(start -0.2032 -0.3048)
							(mid -0.275042 -0.275042)
							(end -0.3048 -0.2032)
						)
						(arc
							(start -0.3048 0.2032)
							(mid -0.275042 0.275042)
							(end -0.2032 0.3048)
						)
						(arc
							(start 0.2032 0.3048)
							(mid 0.275042 0.275042)
							(end 0.3048 0.2032)
						)
					)
					(width 0)
					(fill yes)
				)
			)
		)
		(pad "2" smd custom
			(at 0 0.4445 270)
			(size 0.1524 0.1524)
			(layers "F.Cu" "F.Mask" "F.Paste")
			(net "RESET_CT")
			(options
				(clearance outline)
				(anchor circle)
			)
			(primitives
				(gr_poly
					(pts
						(arc
							(start 0.3048 -0.2032)
							(mid 0.275042 -0.275042)
							(end 0.2032 -0.3048)
						)
						(arc
							(start -0.2032 -0.3048)
							(mid -0.275042 -0.275042)
							(end -0.3048 -0.2032)
						)
						(arc
							(start -0.3048 0.2032)
							(mid -0.275042 0.275042)
							(end -0.2032 0.3048)
						)
						(arc
							(start 0.2032 0.3048)
							(mid 0.275042 0.275042)
							(end 0.3048 0.2032)
						)
					)
					(width 0)
					(fill yes)
				)
			)
		)
	)
	(footprint ""
		(layer "F.Cu")
		(at 14.361414 -59.127644)
		(property "Reference" "R692"
			(at 0 0 0)
			(layer "F.SilkS")
			(hide yes)
			(effects
				(font
					(size 1.27 1.27)
				)
			)
		)
		(property "Value" "0R2J-2-GP"
			(at 0.064008 -3.993896 0)
			(unlocked yes)
			(layer "F.Fab")
			(hide yes)
			(effects
				(font
					(size 1.016 1.016)
					(thickness 0.1524)
				)
			)
		)
		(property "Device Type" "R402H16"
			(at 0.064008 -5.517896 0)
			(unlocked yes)
			(layer "F.Fab")
			(hide yes)
			(effects
				(font
					(size 1.016 1.016)
					(thickness 0.1524)
				)
			)
		)
		(duplicate_pad_numbers_are_jumpers no)
		(fp_line
			(start -0.508 -0.9398)
			(end -0.508 0.9398)
			(stroke
				(width 0.1524)
				(type default)
			)
			(layer "F.SilkS")
		)
		(fp_line
			(start 0.508 -0.9398)
			(end -0.508 -0.9398)
			(stroke
				(width 0.1524)
				(type default)
			)
			(layer "F.SilkS")
		)
		(fp_rect
			(start -0.508 0.9398)
			(end 0.508 -0.9398)
			(stroke
				(width 0)
				(type default)
			)
			(fill no)
			(layer "F.CrtYd")
		)
		(fp_rect
			(start -0.508 0.9398)
			(end 0.508 -0.9398)
			(stroke
				(width 0)
				(type default)
			)
			(fill no)
			(layer "F.Fab")
		)
		(pad "1" smd custom
			(at 0 -0.4445)
			(size 0.1397 0.1397)
			(layers "F.Cu" "F.Mask" "F.Paste")
			(net "MB0_HS_ENABLE_R")
			(options
				(clearance outline)
				(anchor circle)
			)
			(primitives
				(gr_poly
					(pts
						(arc
							(start -0.1778 -0.2794)
							(mid -0.249642 -0.249642)
							(end -0.2794 -0.1778)
						)
						(arc
							(start -0.2794 0.1778)
							(mid -0.249642 0.249642)
							(end -0.1778 0.2794)
						)
						(arc
							(start 0.1778 0.2794)
							(mid 0.249642 0.249642)
							(end 0.2794 0.1778)
						)
						(arc
							(start 0.2794 -0.1778)
							(mid 0.249642 -0.249642)
							(end 0.1778 -0.2794)
						)
					)
					(width 0)
					(fill yes)
				)
			)
		)
		(pad "2" smd custom
			(at 0 0.4445)
			(size 0.1397 0.1397)
			(layers "F.Cu" "F.Mask" "F.Paste")
			(net "MB0_HS_ENABLE")
			(options
				(clearance outline)
				(anchor circle)
			)
			(primitives
				(gr_poly
					(pts
						(arc
							(start -0.1778 -0.2794)
							(mid -0.249642 -0.249642)
							(end -0.2794 -0.1778)
						)
						(arc
							(start -0.2794 0.1778)
							(mid -0.249642 0.249642)
							(end -0.1778 0.2794)
						)
						(arc
							(start 0.1778 0.2794)
							(mid 0.249642 0.249642)
							(end 0.2794 0.1778)
						)
						(arc
							(start 0.2794 -0.1778)
							(mid 0.249642 -0.249642)
							(end 0.1778 -0.2794)
						)
					)
					(width 0)
					(fill yes)
				)
			)
		)
	)
	(footprint ""
		(layer "F.Cu")
		(at 203.691236 -73.519284)
		(property "Reference" "R230"
			(at 0 0 0)
			(layer "F.SilkS")
			(hide yes)
			(effects
				(font
					(size 1.27 1.27)
				)
			)
		)
		(property "Value" "10KR2F-2-GP"
			(at 0.064008 -3.993896 0)
			(unlocked yes)
			(layer "F.Fab")
			(hide yes)
			(effects
				(font
					(size 1.016 1.016)
					(thickness 0.1524)
				)
			)
		)
		(property "Device Type" "R402H16"
			(at 0.064008 -5.517896 0)
			(unlocked yes)
			(layer "F.Fab")
			(hide yes)
			(effects
				(font
					(size 1.016 1.016)
					(thickness 0.1524)
				)
			)
		)
		(duplicate_pad_numbers_are_jumpers no)
		(fp_line
			(start -0.508 -0.9398)
			(end -0.508 0.9398)
			(stroke
				(width 0.1524)
				(type default)
			)
			(layer "F.SilkS")
		)
		(fp_line
			(start 0.508 -0.9398)
			(end -0.508 -0.9398)
			(stroke
				(width 0.1524)
				(type default)
			)
			(layer "F.SilkS")
		)
		(fp_rect
			(start -0.508 0.9398)
			(end 0.508 -0.9398)
			(stroke
				(width 0)
				(type default)
			)
			(fill no)
			(layer "F.CrtYd")
		)
		(fp_rect
			(start -0.508 0.9398)
			(end 0.508 -0.9398)
			(stroke
				(width 0)
				(type default)
			)
			(fill no)
			(layer "F.Fab")
		)
		(pad "1" smd custom
			(at 0 -0.4445)
			(size 0.1397 0.1397)
			(layers "F.Cu" "F.Mask" "F.Paste")
			(net "P1V8_C")
			(options
				(clearance outline)
				(anchor circle)
			)
			(primitives
				(gr_poly
					(pts
						(arc
							(start -0.1778 -0.2794)
							(mid -0.249642 -0.249642)
							(end -0.2794 -0.1778)
						)
						(arc
							(start -0.2794 0.1778)
							(mid -0.249642 0.249642)
							(end -0.1778 0.2794)
						)
						(arc
							(start 0.1778 0.2794)
							(mid 0.249642 0.249642)
							(end 0.2794 0.1778)
						)
						(arc
							(start 0.2794 -0.1778)
							(mid 0.249642 -0.249642)
							(end 0.1778 -0.2794)
						)
					)
					(width 0)
					(fill yes)
				)
			)
		)
		(pad "2" smd custom
			(at 0 0.4445)
			(size 0.1397 0.1397)
			(layers "F.Cu" "F.Mask" "F.Paste")
			(net "XM_NOR_CS_N")
			(options
				(clearance outline)
				(anchor circle)
			)
			(primitives
				(gr_poly
					(pts
						(arc
							(start -0.1778 -0.2794)
							(mid -0.249642 -0.249642)
							(end -0.2794 -0.1778)
						)
						(arc
							(start -0.2794 0.1778)
							(mid -0.249642 0.249642)
							(end -0.1778 0.2794)
						)
						(arc
							(start 0.1778 0.2794)
							(mid 0.249642 0.249642)
							(end 0.2794 0.1778)
						)
						(arc
							(start 0.2794 -0.1778)
							(mid 0.249642 -0.249642)
							(end 0.1778 -0.2794)
						)
					)
					(width 0)
					(fill yes)
				)
			)
		)
	)
)
